(kicad_pcb
	(version 20260206)
	(generator "pcbnew")
	(generator_version "10.0")
	(general
		(thickness 1.6)
		(legacy_teardrops no)
	)
	(paper "A4")
	(title_block
		(title "01162023_DA0F0TEBIF0_F0T_Expander_BD_F_brd_V02_OCP.brd")
		(comment 1 "Grand Teton / footprints 2931-2935 of 9728")
	)
	(layers
		(0 "F.Cu" signal "TOP")
		(4 "In1.Cu" signal "GND")
		(6 "In2.Cu" signal "VCC")
		(8 "In3.Cu" signal "VCC1")
		(10 "In4.Cu" signal "GND1")
		(12 "In5.Cu" signal "IN1")
		(14 "In6.Cu" signal "GND2")
		(16 "In7.Cu" signal "IN2")
		(18 "In8.Cu" signal "GND3")
		(20 "In9.Cu" signal "IN3")
		(22 "In10.Cu" signal "GND4")
		(24 "In11.Cu" signal "IN4")
		(26 "In12.Cu" signal "GND5")
		(28 "In13.Cu" signal "IN5")
		(30 "In14.Cu" signal "GND6")
		(32 "In15.Cu" signal "IN6")
		(34 "In16.Cu" signal "GND7")
		(2 "B.Cu" signal "BOTTOM")
		(9 "F.Adhes" user "F.Adhesive")
		(11 "B.Adhes" user "B.Adhesive")
		(13 "F.Paste" user "Package Geometry/Pastemask Top")
		(15 "B.Paste" user "Package Geometry/Pastemask Bottom")
		(5 "F.SilkS" user "Ref Des/Silkscreen Top")
		(7 "B.SilkS" user "Ref Des/Silkscreen Bottom")
		(1 "F.Mask" user "Board Geometry/Soldermask Top")
		(3 "B.Mask" user "Board Geometry/Soldermask Bottom")
		(17 "Dwgs.User" user "User.Drawings")
		(19 "Cmts.User" user "User.Comments")
		(21 "Eco1.User" user "User.Eco1")
		(23 "Eco2.User" user "User.Eco2")
		(25 "Edge.Cuts" user "Board Geometry/Outline")
		(27 "Margin" user)
		(31 "F.CrtYd" user "Package Geometry/Place Bound Top")
		(29 "B.CrtYd" user "Package Geometry/Place Bound Bottom")
		(35 "F.Fab" user "Ref Des/Assembly Top")
		(33 "B.Fab" user "Ref Des/Assembly Bottom")
	)
	(footprint ""
		(layer "F.Cu")
		(at 33.287716 -291.619432)
		(property "Reference" "C3042"
			(at 0 0 0)
			(layer "F.SilkS")
			(hide yes)
			(effects
				(font
					(size 1.27 1.27)
				)
			)
		)
		(property "Value" ""
			(at 0 0 0)
			(layer "F.Fab")
			(effects
				(font
					(size 1.27 1.27)
				)
			)
		)
		(duplicate_pad_numbers_are_jumpers no)
		(fp_line
			(start -1.2954 -0.5842)
			(end 1.2954 -0.5842)
			(stroke
				(width 0.1524)
				(type default)
			)
			(layer "F.SilkS")
		)
		(fp_line
			(start -1.2954 0.5842)
			(end -1.2954 -0.5842)
			(stroke
				(width 0.1524)
				(type default)
			)
			(layer "F.SilkS")
		)
		(fp_line
			(start 1.2954 -0.5842)
			(end 1.2954 0.5842)
			(stroke
				(width 0.1524)
				(type default)
			)
			(layer "F.SilkS")
		)
		(fp_line
			(start 1.2954 0.5842)
			(end -1.2954 0.5842)
			(stroke
				(width 0.1524)
				(type default)
			)
			(layer "F.SilkS")
		)
		(fp_line
			(start -1.1938 -0.4064)
			(end -0.8636 -0.4064)
			(stroke
				(width 0.1)
				(type default)
			)
			(layer "F.Fab")
		)
		(fp_line
			(start -1.1938 0.4064)
			(end -1.1938 -0.4064)
			(stroke
				(width 0.1)
				(type default)
			)
			(layer "F.Fab")
		)
		(fp_line
			(start -0.8636 -0.4572)
			(end 0.8636 -0.4572)
			(stroke
				(width 0.1)
				(type default)
			)
			(layer "F.Fab")
		)
		(fp_line
			(start -0.8636 -0.4064)
			(end -0.8636 -0.4572)
			(stroke
				(width 0.1)
				(type default)
			)
			(layer "F.Fab")
		)
		(fp_line
			(start -0.8636 0.4064)
			(end -1.1938 0.4064)
			(stroke
				(width 0.1)
				(type default)
			)
			(layer "F.Fab")
		)
		(fp_line
			(start -0.8636 0.4572)
			(end -0.8636 0.4064)
			(stroke
				(width 0.1)
				(type default)
			)
			(layer "F.Fab")
		)
		(fp_line
			(start 0.8636 -0.4572)
			(end 0.8636 -0.4064)
			(stroke
				(width 0.1)
				(type default)
			)
			(layer "F.Fab")
		)
		(fp_line
			(start 0.8636 -0.4064)
			(end 1.1938 -0.4064)
			(stroke
				(width 0.1)
				(type default)
			)
			(layer "F.Fab")
		)
		(fp_line
			(start 0.8636 0.4064)
			(end 0.8636 0.4572)
			(stroke
				(width 0.1)
				(type default)
			)
			(layer "F.Fab")
		)
		(fp_line
			(start 0.8636 0.4572)
			(end -0.8636 0.4572)
			(stroke
				(width 0.1)
				(type default)
			)
			(layer "F.Fab")
		)
		(fp_line
			(start 1.1938 -0.4064)
			(end 1.1938 0.4064)
			(stroke
				(width 0.1)
				(type default)
			)
			(layer "F.Fab")
		)
		(fp_line
			(start 1.1938 0.4064)
			(end 0.8636 0.4064)
			(stroke
				(width 0.1)
				(type default)
			)
			(layer "F.Fab")
		)
		(pad "1" smd rect
			(at -0.7366 0 270)
			(size 0.7112 0.8128)
			(layers "F.Cu" "F.Mask" "F.Paste")
			(net "PCEPLL4_VDDA18_PEX0")
		)
		(pad "2" smd rect
			(at 0.7366 0 270)
			(size 0.7112 0.8128)
			(layers "F.Cu" "F.Mask" "F.Paste")
			(net "GND")
		)
	)
	(footprint ""
		(layer "F.Cu")
		(at 228.446838 -277.791926 180)
		(property "Reference" "U90"
			(at -2.584958 -6.057392 0)
			(unlocked yes)
			(layer "F.SilkS")
			(effects
				(font
					(size 0.7874 0.5842)
					(thickness 0.1524)
				)
			)
		)
		(property "Value" ""
			(at 0 0 180)
			(layer "F.Fab")
			(effects
				(font
					(size 1.27 1.27)
				)
			)
		)
		(duplicate_pad_numbers_are_jumpers no)
		(fp_line
			(start 1.500124 1.500124)
			(end 1.004062 1.500124)
			(stroke
				(width 0.1524)
				(type default)
			)
			(layer "F.SilkS")
		)
		(fp_line
			(start 1.500124 1.004062)
			(end 1.500124 1.500124)
			(stroke
				(width 0.1524)
				(type default)
			)
			(layer "F.SilkS")
		)
		(fp_line
			(start 1.500124 -1.500124)
			(end 1.500124 -1.004062)
			(stroke
				(width 0.1524)
				(type default)
			)
			(layer "F.SilkS")
		)
		(fp_line
			(start 1.004062 -1.500124)
			(end 1.500124 -1.500124)
			(stroke
				(width 0.1524)
				(type default)
			)
			(layer "F.SilkS")
		)
		(fp_line
			(start -1.004062 1.500124)
			(end -1.500124 1.500124)
			(stroke
				(width 0.1524)
				(type default)
			)
			(layer "F.SilkS")
		)
		(fp_line
			(start -1.500124 1.500124)
			(end -1.500124 1.004062)
			(stroke
				(width 0.1524)
				(type default)
			)
			(layer "F.SilkS")
		)
		(fp_line
			(start -1.500124 -1.004062)
			(end -1.500124 -1.500124)
			(stroke
				(width 0.1524)
				(type default)
			)
			(layer "F.SilkS")
		)
		(fp_line
			(start -1.500124 -1.500124)
			(end -1.004062 -1.500124)
			(stroke
				(width 0.1524)
				(type default)
			)
			(layer "F.SilkS")
		)
		(fp_poly
			(pts
				(xy -1.307084 -2.106676) (xy -2.323084 -2.106676) (xy -1.815084 -1.090676)
			)
			(stroke
				(width 0)
				(type default)
			)
			(fill yes)
			(layer "F.SilkS")
		)
		(fp_line
			(start 1.500124 1.500124)
			(end -1.500124 1.500124)
			(stroke
				(width 0.1)
				(type default)
			)
			(layer "F.Fab")
		)
		(fp_line
			(start 1.500124 -1.500124)
			(end 1.500124 1.500124)
			(stroke
				(width 0.1)
				(type default)
			)
			(layer "F.Fab")
		)
		(fp_line
			(start -1.500124 1.500124)
			(end -1.500124 -1.500124)
			(stroke
				(width 0.1)
				(type default)
			)
			(layer "F.Fab")
		)
		(fp_line
			(start -1.500124 -1.500124)
			(end 1.500124 -1.500124)
			(stroke
				(width 0.1)
				(type default)
			)
			(layer "F.Fab")
		)
		(fp_poly
			(pts
				(xy -2.847848 -1.258062) (xy -2.847848 -0.242062) (xy -1.831848 -0.750062)
			)
			(stroke
				(width 0)
				(type default)
			)
			(fill yes)
			(layer "F.Fab")
		)
		(pad "1" smd rect
			(at -1.400048 -0.750062 90)
			(size 0.2286 0.6096)
			(layers "F.Cu" "F.Mask" "F.Paste")
			(net "PEX1_P1V25_ADC_A1")
		)
		(pad "2" smd rect
			(at -1.400048 -0.249936 90)
			(size 0.2286 0.6096)
			(layers "F.Cu" "F.Mask" "F.Paste")
			(net "PEX1_P1V25_ADC_A0")
		)
		(pad "3" smd rect
			(at -1.400048 0.249936 90)
			(size 0.2286 0.6096)
			(layers "F.Cu" "F.Mask" "F.Paste")
			(net "PEX1_P1V25_ADC_ALERT_N")
		)
		(pad "4" smd rect
			(at -1.400048 0.750062 90)
			(size 0.2286 0.6096)
			(layers "F.Cu" "F.Mask" "F.Paste")
			(net "SMB_PEX1_P1V25_ADC_SDA")
		)
		(pad "5" smd rect
			(at -0.750062 1.400048 180)
			(size 0.2286 0.6096)
			(layers "F.Cu" "F.Mask" "F.Paste")
			(net "SMB_PEX1_P1V25_ADC_SCL")
		)
		(pad "6" smd rect
			(at -0.249936 1.400048 180)
			(size 0.2286 0.6096)
			(layers "F.Cu" "F.Mask" "F.Paste")
			(net "Net_8612")
		)
		(pad "7" smd rect
			(at 0.249936 1.400048 180)
			(size 0.2286 0.6096)
			(layers "F.Cu" "F.Mask" "F.Paste")
			(net "Net_8611")
		)
		(pad "8" smd rect
			(at 0.750062 1.400048 180)
			(size 0.2286 0.6096)
			(layers "F.Cu" "F.Mask" "F.Paste")
			(net "Net_8610")
		)
		(pad "9" smd rect
			(at 1.400048 0.750062 90)
			(size 0.2286 0.6096)
			(layers "F.Cu" "F.Mask" "F.Paste")
			(net "P3V3_AUX")
		)
		(pad "10" smd rect
			(at 1.400048 0.249936 90)
			(size 0.2286 0.6096)
			(layers "F.Cu" "F.Mask" "F.Paste")
			(net "GND")
		)
		(pad "11" smd rect
			(at 1.400048 -0.249936 90)
			(size 0.2286 0.6096)
			(layers "F.Cu" "F.Mask" "F.Paste")
			(net "P1V25_PEX1_R")
		)
		(pad "12" smd rect
			(at 1.400048 -0.750062 90)
			(size 0.2286 0.6096)
			(layers "F.Cu" "F.Mask" "F.Paste")
			(net "P12V_PEX1_P1V25_VIN_N")
		)
		(pad "13" smd rect
			(at 0.750062 -1.400048 180)
			(size 0.2286 0.6096)
			(layers "F.Cu" "F.Mask" "F.Paste")
			(net "P12V_PEX1_P1V25_VIN_P")
		)
		(pad "14" smd rect
			(at 0.249936 -1.400048 180)
			(size 0.2286 0.6096)
			(layers "F.Cu" "F.Mask" "F.Paste")
			(net "Net_8609")
		)
		(pad "15" smd rect
			(at -0.249936 -1.400048 180)
			(size 0.2286 0.6096)
			(layers "F.Cu" "F.Mask" "F.Paste")
			(net "Net_8608")
		)
		(pad "16" smd rect
			(at -0.750062 -1.400048 180)
			(size 0.2286 0.6096)
			(layers "F.Cu" "F.Mask" "F.Paste")
			(net "Net_8607")
		)
		(pad "TH" smd rect
			(at 0 0 180)
			(size 1.7018 1.7018)
			(layers "F.Cu" "F.Mask" "F.Paste")
			(net "GND")
		)
		(zone
			(layer "F.Cu")
			(hatch none 0.5)
			(connect_pads
				(clearance 0)
			)
			(min_thickness 0.25)
			(keepout
				(tracks not_allowed)
				(vias allowed)
				(pads allowed)
				(copperpour not_allowed)
				(footprints allowed)
			)
			(placement
				(enabled no)
				(sheetname "")
			)
			(fill
				(thermal_gap 0.5)
				(thermal_bridge_width 0.5)
				(island_removal_mode 0)
			)
			(polygon
				(pts
					(xy 229.491286 -277.766526) (xy 229.491286 -276.747478) (xy 227.40239 -276.747478) (xy 227.40239 -278.836374)
					(xy 229.491286 -278.836374) (xy 229.491286 -277.791926) (xy 229.348538 -277.791926) (xy 229.348538 -278.693626)
					(xy 227.545138 -278.693626) (xy 227.545138 -276.890226) (xy 229.348538 -276.890226) (xy 229.348538 -277.766526)
				)
			)
		)
	)
	(footprint ""
		(layer "F.Cu")
		(at 358.013 -215.392 180)
		(property "Reference" "R4093"
			(at 0 0 180)
			(layer "F.SilkS")
			(hide yes)
			(effects
				(font
					(size 1.27 1.27)
				)
			)
		)
		(property "Value" ""
			(at 0 0 180)
			(layer "F.Fab")
			(effects
				(font
					(size 1.27 1.27)
				)
			)
		)
		(duplicate_pad_numbers_are_jumpers no)
		(fp_line
			(start 0.7874 0.4064)
			(end -0.7874 0.4064)
			(stroke
				(width 0.1524)
				(type default)
			)
			(layer "F.SilkS")
		)
		(fp_line
			(start 0.7874 -0.4064)
			(end 0.7874 0.4064)
			(stroke
				(width 0.1524)
				(type default)
			)
			(layer "F.SilkS")
		)
		(fp_line
			(start -0.7874 0.4064)
			(end -0.7874 -0.4064)
			(stroke
				(width 0.1524)
				(type default)
			)
			(layer "F.SilkS")
		)
		(fp_line
			(start -0.7874 -0.4064)
			(end 0.7874 -0.4064)
			(stroke
				(width 0.1524)
				(type default)
			)
			(layer "F.SilkS")
		)
		(fp_line
			(start 0.67945 0.3048)
			(end 0.120396 0.3048)
			(stroke
				(width 0.1)
				(type default)
			)
			(layer "F.Fab")
		)
		(fp_line
			(start 0.67945 -0.3048)
			(end 0.67945 0.3048)
			(stroke
				(width 0.1)
				(type default)
			)
			(layer "F.Fab")
		)
		(fp_line
			(start 0.12065 -0.2794)
			(end 0.12065 -0.3048)
			(stroke
				(width 0.1)
				(type default)
			)
			(layer "F.Fab")
		)
		(fp_line
			(start 0.12065 -0.3048)
			(end 0.67945 -0.3048)
			(stroke
				(width 0.1)
				(type default)
			)
			(layer "F.Fab")
		)
		(fp_line
			(start 0.120396 0.3048)
			(end 0.120396 0.2794)
			(stroke
				(width 0.1)
				(type default)
			)
			(layer "F.Fab")
		)
		(fp_line
			(start 0.120396 0.2794)
			(end -0.12065 0.2794)
			(stroke
				(width 0.1)
				(type default)
			)
			(layer "F.Fab")
		)
		(fp_line
			(start -0.12065 0.3048)
			(end -0.67945 0.3048)
			(stroke
				(width 0.1)
				(type default)
			)
			(layer "F.Fab")
		)
		(fp_line
			(start -0.12065 0.2794)
			(end -0.12065 0.3048)
			(stroke
				(width 0.1)
				(type default)
			)
			(layer "F.Fab")
		)
		(fp_line
			(start -0.12065 -0.2794)
			(end 0.12065 -0.2794)
			(stroke
				(width 0.1)
				(type default)
			)
			(layer "F.Fab")
		)
		(fp_line
			(start -0.12065 -0.305054)
			(end -0.12065 -0.2794)
			(stroke
				(width 0.1)
				(type default)
			)
			(layer "F.Fab")
		)
		(fp_line
			(start -0.67945 0.3048)
			(end -0.67945 -0.305054)
			(stroke
				(width 0.1)
				(type default)
			)
			(layer "F.Fab")
		)
		(fp_line
			(start -0.67945 -0.305054)
			(end -0.12065 -0.305054)
			(stroke
				(width 0.1)
				(type default)
			)
			(layer "F.Fab")
		)
		(pad "1" smd circle
			(at -0.40005 0 180)
			(size 0 0)
			(layers "F.Cu" "F.Mask" "F.Paste")
			(net "PRSNT_NIC1_FPGA_R_N")
		)
		(pad "2" smd circle
			(at 0.40005 0 180)
			(size 0 0)
			(layers "F.Cu" "F.Mask" "F.Paste")
			(net "PRSNT_NIC1_FPGA_N")
		)
	)
	(footprint ""
		(layer "F.Cu")
		(at 228.582474 -136.669272 -90)
		(property "Reference" "R4191"
			(at 0 0 270)
			(layer "F.SilkS")
			(hide yes)
			(effects
				(font
					(size 1.27 1.27)
				)
			)
		)
		(property "Value" ""
			(at 0 0 270)
			(layer "F.Fab")
			(effects
				(font
					(size 1.27 1.27)
				)
			)
		)
		(duplicate_pad_numbers_are_jumpers no)
		(fp_line
			(start -0.7874 0.4064)
			(end -0.7874 -0.4064)
			(stroke
				(width 0.1524)
				(type default)
			)
			(layer "F.SilkS")
		)
		(fp_line
			(start 0.7874 0.4064)
			(end -0.7874 0.4064)
			(stroke
				(width 0.1524)
				(type default)
			)
			(layer "F.SilkS")
		)
		(fp_line
			(start -0.7874 -0.4064)
			(end 0.7874 -0.4064)
			(stroke
				(width 0.1524)
				(type default)
			)
			(layer "F.SilkS")
		)
		(fp_line
			(start 0.7874 -0.4064)
			(end 0.7874 0.4064)
			(stroke
				(width 0.1524)
				(type default)
			)
			(layer "F.SilkS")
		)
		(fp_line
			(start -0.67945 0.3048)
			(end -0.67945 -0.305054)
			(stroke
				(width 0.1)
				(type default)
			)
			(layer "F.Fab")
		)
		(fp_line
			(start -0.12065 0.3048)
			(end -0.67945 0.3048)
			(stroke
				(width 0.1)
				(type default)
			)
			(layer "F.Fab")
		)
		(fp_line
			(start 0.120396 0.3048)
			(end 0.120396 0.2794)
			(stroke
				(width 0.1)
				(type default)
			)
			(layer "F.Fab")
		)
		(fp_line
			(start 0.67945 0.3048)
			(end 0.120396 0.3048)
			(stroke
				(width 0.1)
				(type default)
			)
			(layer "F.Fab")
		)
		(fp_line
			(start -0.12065 0.2794)
			(end -0.12065 0.3048)
			(stroke
				(width 0.1)
				(type default)
			)
			(layer "F.Fab")
		)
		(fp_line
			(start 0.120396 0.2794)
			(end -0.12065 0.2794)
			(stroke
				(width 0.1)
				(type default)
			)
			(layer "F.Fab")
		)
		(fp_line
			(start -0.12065 -0.2794)
			(end 0.12065 -0.2794)
			(stroke
				(width 0.1)
				(type default)
			)
			(layer "F.Fab")
		)
		(fp_line
			(start 0.12065 -0.2794)
			(end 0.12065 -0.3048)
			(stroke
				(width 0.1)
				(type default)
			)
			(layer "F.Fab")
		)
		(fp_line
			(start 0.12065 -0.3048)
			(end 0.67945 -0.3048)
			(stroke
				(width 0.1)
				(type default)
			)
			(layer "F.Fab")
		)
		(fp_line
			(start 0.67945 -0.3048)
			(end 0.67945 0.3048)
			(stroke
				(width 0.1)
				(type default)
			)
			(layer "F.Fab")
		)
		(fp_line
			(start -0.67945 -0.305054)
			(end -0.12065 -0.305054)
			(stroke
				(width 0.1)
				(type default)
			)
			(layer "F.Fab")
		)
		(fp_line
			(start -0.12065 -0.305054)
			(end -0.12065 -0.2794)
			(stroke
				(width 0.1)
				(type default)
			)
			(layer "F.Fab")
		)
		(pad "1" smd circle
			(at -0.40005 0 270)
			(size 0 0)
			(layers "F.Cu" "F.Mask" "F.Paste")
			(net "CLK_CK440_PEX_SMB_ADDR0")
		)
		(pad "2" smd circle
			(at 0.40005 0 270)
			(size 0 0)
			(layers "F.Cu" "F.Mask" "F.Paste")
			(net "P3V3")
		)
	)
	(footprint ""
		(layer "F.Cu")
		(at 315.147198 -36.686998 90)
		(property "Reference" "C3671"
			(at 0 0 90)
			(layer "F.SilkS")
			(hide yes)
			(effects
				(font
					(size 1.27 1.27)
				)
			)
		)
		(property "Value" ""
			(at 0 0 90)
			(layer "F.Fab")
			(effects
				(font
					(size 1.27 1.27)
				)
			)
		)
		(duplicate_pad_numbers_are_jumpers no)
		(fp_line
			(start 0.7874 -0.4064)
			(end 0.7874 0.4064)
			(stroke
				(width 0.1524)
				(type default)
			)
			(layer "F.SilkS")
		)
		(fp_line
			(start -0.7874 -0.4064)
			(end 0.7874 -0.4064)
			(stroke
				(width 0.1524)
				(type default)
			)
			(layer "F.SilkS")
		)
		(fp_line
			(start 0.7874 0.4064)
			(end -0.7874 0.4064)
			(stroke
				(width 0.1524)
				(type default)
			)
			(layer "F.SilkS")
		)
		(fp_line
			(start -0.7874 0.4064)
			(end -0.7874 -0.4064)
			(stroke
				(width 0.1524)
				(type default)
			)
			(layer "F.SilkS")
		)
		(fp_line
			(start -0.12065 -0.305054)
			(end -0.12065 -0.2794)
			(stroke
				(width 0.1)
				(type default)
			)
			(layer "F.Fab")
		)
		(fp_line
			(start -0.67945 -0.305054)
			(end -0.12065 -0.305054)
			(stroke
				(width 0.1)
				(type default)
			)
			(layer "F.Fab")
		)
		(fp_line
			(start 0.67945 -0.3048)
			(end 0.67945 0.3048)
			(stroke
				(width 0.1)
				(type default)
			)
			(layer "F.Fab")
		)
		(fp_line
			(start 0.12065 -0.3048)
			(end 0.67945 -0.3048)
			(stroke
				(width 0.1)
				(type default)
			)
			(layer "F.Fab")
		)
		(fp_line
			(start 0.12065 -0.2794)
			(end 0.12065 -0.3048)
			(stroke
				(width 0.1)
				(type default)
			)
			(layer "F.Fab")
		)
		(fp_line
			(start -0.12065 -0.2794)
			(end 0.12065 -0.2794)
			(stroke
				(width 0.1)
				(type default)
			)
			(layer "F.Fab")
		)
		(fp_line
			(start 0.120396 0.2794)
			(end -0.12065 0.2794)
			(stroke
				(width 0.1)
				(type default)
			)
			(layer "F.Fab")
		)
		(fp_line
			(start -0.12065 0.2794)
			(end -0.12065 0.3048)
			(stroke
				(width 0.1)
				(type default)
			)
			(layer "F.Fab")
		)
		(fp_line
			(start 0.67945 0.3048)
			(end 0.120396 0.3048)
			(stroke
				(width 0.1)
				(type default)
			)
			(layer "F.Fab")
		)
		(fp_line
			(start 0.120396 0.3048)
			(end 0.120396 0.2794)
			(stroke
				(width 0.1)
				(type default)
			)
			(layer "F.Fab")
		)
		(fp_line
			(start -0.12065 0.3048)
			(end -0.67945 0.3048)
			(stroke
				(width 0.1)
				(type default)
			)
			(layer "F.Fab")
		)
		(fp_line
			(start -0.67945 0.3048)
			(end -0.67945 -0.305054)
			(stroke
				(width 0.1)
				(type default)
			)
			(layer "F.Fab")
		)
		(pad "1" smd circle
			(at -0.40005 0 90)
			(size 0 0)
			(layers "F.Cu" "F.Mask" "F.Paste")
			(net "P3V3_AUX")
		)
		(pad "2" smd circle
			(at 0.40005 0 90)
			(size 0 0)
			(layers "F.Cu" "F.Mask" "F.Paste")
			(net "GND")
		)
	)
)
